#ISCELL
  pure_quanta quanta_title_block_c *
  *
#ISCELL
  standard offpage *
  page442_i1
#ISCELL
  pure_quanta_power universal_gnd *
  page442_i18
#CELL
  pure_quanta q_res *
  page442_i19
#ISCELL
  standard offpage *
  page442_i2
#ISCELL
  pure_quanta_power universal_gnd *
  page442_i20
#ISCELL
  pure_quanta_power p1v0 *
  page442_i21
#CELL
  pure_quanta q_cap *
  page442_i22
#ISCELL
  pure_quanta_power universal_gnd *
  page442_i23
#ISCELL
  pure_quanta_power universal_gnd *
  page442_i24
#CELL
  pure_quanta q_res *
  page442_i3
#CELL
  pure_quanta q_res *
  page442_i4
#CELL
  pure_quanta m24m02drmn6tp *
  page442_i5
